# SCM (Grand Teton) — schematic netlist excerpt (pin names and nets, part order shuffled) for the footprints in the layout excerpt that follows; sources: Cadence DE-HDL packaged netlist, KiCad conversion of 12092022_DA0F0TMDCD0_F0T_Management_Board_D_brd_V3_OCP.brd

R428  Q_RES  2.2K 5% CHIP  pkg 0402LF  page 27 : A = P3V3_AUX ; B = SMB_BMC_MM13_SDA
R690  Q_RES  33.2 1% CHIP  pkg 0402LF  page 35 : A = IRQ_SGPIO_R_N ; B = IRQ_SGPIO_N

(kicad_pcb
	(version 20260206)
	(generator "pcbnew")
	(generator_version "10.0")
	(general
		(thickness 1.6)
		(legacy_teardrops no)
	)
	(paper "A4")
	(title_block
		(title "12092022_DA0F0TMDCD0_F0T_Management_Board_D_brd_V3_OCP.brd")
		(comment 1 "Grand Teton / footprints 729-730 of 1440")
	)
	(layers
		(0 "F.Cu" signal "TOP")
		(4 "In1.Cu" signal "GND")
		(6 "In2.Cu" signal "IN1")
		(8 "In3.Cu" signal "GND1")
		(10 "In4.Cu" signal "IN2")
		(12 "In5.Cu" signal "VCC")
		(14 "In6.Cu" signal "VCC1")
		(16 "In7.Cu" signal "IN3")
		(18 "In8.Cu" signal "GND2")
		(20 "In9.Cu" signal "IN4")
		(22 "In10.Cu" signal "GND3")
		(2 "B.Cu" signal "BOTTOM")
		(9 "F.Adhes" user "F.Adhesive")
		(11 "B.Adhes" user "B.Adhesive")
		(13 "F.Paste" user "Package Geometry/Pastemask Top")
		(15 "B.Paste" user "Package Geometry/Pastemask Bottom")
		(5 "F.SilkS" user "Ref Des/Silkscreen Top")
		(7 "B.SilkS" user "Ref Des/Silkscreen Bottom")
		(1 "F.Mask" user "Board Geometry/Soldermask Top")
		(3 "B.Mask" user "Board Geometry/Soldermask Bottom")
		(17 "Dwgs.User" user "User.Drawings")
		(19 "Cmts.User" user "User.Comments")
		(21 "Eco1.User" user "User.Eco1")
		(23 "Eco2.User" user "User.Eco2")
		(25 "Edge.Cuts" user "Board Geometry/Outline")
		(27 "Margin" user)
		(31 "F.CrtYd" user "Package Geometry/Place Bound Top")
		(29 "B.CrtYd" user "Package Geometry/Place Bound Bottom")
		(35 "F.Fab" user "Ref Des/Assembly Top")
		(33 "B.Fab" user "Ref Des/Assembly Bottom")
	)
	(footprint ""
		(layer "B.Cu")
		(at 38.0238 -46.25594 180)
		(property "Reference" "R428"
			(at 0 0 0)
			(layer "B.SilkS")
			(hide yes)
			(effects
				(font
					(size 1.27 1.27)
				)
				(justify mirror)
			)
		)
		(property "Value" ""
			(at 0 0 0)
			(layer "B.Fab")
			(effects
				(font
					(size 1.27 1.27)
				)
				(justify mirror)
			)
		)
		(duplicate_pad_numbers_are_jumpers no)
		(fp_line
			(start 0.7874 0.4064)
			(end 0.7874 -0.4064)
			(stroke
				(width 0.1524)
				(type default)
			)
			(layer "B.SilkS")
		)
		(fp_line
			(start 0.7874 -0.4064)
			(end -0.7874 -0.4064)
			(stroke
				(width 0.1524)
				(type default)
			)
			(layer "B.SilkS")
		)
		(fp_line
			(start -0.7874 0.4064)
			(end 0.7874 0.4064)
			(stroke
				(width 0.1524)
				(type default)
			)
			(layer "B.SilkS")
		)
		(fp_line
			(start -0.7874 -0.4064)
			(end -0.7874 0.4064)
			(stroke
				(width 0.1524)
				(type default)
			)
			(layer "B.SilkS")
		)
		(fp_line
			(start 0.67945 0.3048)
			(end 0.67945 -0.305054)
			(stroke
				(width 0.1)
				(type default)
			)
			(layer "B.Fab")
		)
		(fp_line
			(start 0.67945 -0.305054)
			(end 0.12065 -0.305054)
			(stroke
				(width 0.1)
				(type default)
			)
			(layer "B.Fab")
		)
		(fp_line
			(start 0.12065 0.3048)
			(end 0.67945 0.3048)
			(stroke
				(width 0.1)
				(type default)
			)
			(layer "B.Fab")
		)
		(fp_line
			(start 0.12065 0.2794)
			(end 0.12065 0.3048)
			(stroke
				(width 0.1)
				(type default)
			)
			(layer "B.Fab")
		)
		(fp_line
			(start 0.12065 -0.2794)
			(end -0.12065 -0.2794)
			(stroke
				(width 0.1)
				(type default)
			)
			(layer "B.Fab")
		)
		(fp_line
			(start 0.12065 -0.305054)
			(end 0.12065 -0.2794)
			(stroke
				(width 0.1)
				(type default)
			)
			(layer "B.Fab")
		)
		(fp_line
			(start -0.120396 0.3048)
			(end -0.120396 0.2794)
			(stroke
				(width 0.1)
				(type default)
			)
			(layer "B.Fab")
		)
		(fp_line
			(start -0.120396 0.2794)
			(end 0.12065 0.2794)
			(stroke
				(width 0.1)
				(type default)
			)
			(layer "B.Fab")
		)
		(fp_line
			(start -0.12065 -0.2794)
			(end -0.12065 -0.3048)
			(stroke
				(width 0.1)
				(type default)
			)
			(layer "B.Fab")
		)
		(fp_line
			(start -0.12065 -0.3048)
			(end -0.67945 -0.3048)
			(stroke
				(width 0.1)
				(type default)
			)
			(layer "B.Fab")
		)
		(fp_line
			(start -0.67945 0.3048)
			(end -0.120396 0.3048)
			(stroke
				(width 0.1)
				(type default)
			)
			(layer "B.Fab")
		)
		(fp_line
			(start -0.67945 -0.3048)
			(end -0.67945 0.3048)
			(stroke
				(width 0.1)
				(type default)
			)
			(layer "B.Fab")
		)
		(pad "1" smd circle
			(at 0.40005 0)
			(size 0 0)
			(layers "B.Cu" "B.Mask" "B.Paste")
			(net "P3V3_AUX")
		)
		(pad "2" smd circle
			(at -0.40005 0)
			(size 0 0)
			(layers "B.Cu" "B.Mask" "B.Paste")
			(net "SMB_BMC_MM13_SDA")
		)
	)
	(footprint ""
		(layer "B.Cu")
		(at 13.2588 -83.693 90)
		(property "Reference" "R690"
			(at 0 0 90)
			(layer "B.SilkS")
			(hide yes)
			(effects
				(font
					(size 1.27 1.27)
				)
				(justify mirror)
			)
		)
		(property "Value" ""
			(at 0 0 90)
			(layer "B.Fab")
			(effects
				(font
					(size 1.27 1.27)
				)
				(justify mirror)
			)
		)
		(duplicate_pad_numbers_are_jumpers no)
		(fp_line
			(start 0.7874 -0.4064)
			(end -0.7874 -0.4064)
			(stroke
				(width 0.1524)
				(type default)
			)
			(layer "B.SilkS")
		)
		(fp_line
			(start -0.7874 -0.4064)
			(end -0.7874 0.4064)
			(stroke
				(width 0.1524)
				(type default)
			)
			(layer "B.SilkS")
		)
		(fp_line
			(start 0.7874 0.4064)
			(end 0.7874 -0.4064)
			(stroke
				(width 0.1524)
				(type default)
			)
			(layer "B.SilkS")
		)
		(fp_line
			(start -0.7874 0.4064)
			(end 0.7874 0.4064)
			(stroke
				(width 0.1524)
				(type default)
			)
			(layer "B.SilkS")
		)
		(fp_line
			(start 0.67945 -0.305054)
			(end 0.12065 -0.305054)
			(stroke
				(width 0.1)
				(type default)
			)
			(layer "B.Fab")
		)
		(fp_line
			(start 0.12065 -0.305054)
			(end 0.12065 -0.2794)
			(stroke
				(width 0.1)
				(type default)
			)
			(layer "B.Fab")
		)
		(fp_line
			(start -0.12065 -0.3048)
			(end -0.67945 -0.3048)
			(stroke
				(width 0.1)
				(type default)
			)
			(layer "B.Fab")
		)
		(fp_line
			(start -0.67945 -0.3048)
			(end -0.67945 0.3048)
			(stroke
				(width 0.1)
				(type default)
			)
			(layer "B.Fab")
		)
		(fp_line
			(start 0.12065 -0.2794)
			(end -0.12065 -0.2794)
			(stroke
				(width 0.1)
				(type default)
			)
			(layer "B.Fab")
		)
		(fp_line
			(start -0.12065 -0.2794)
			(end -0.12065 -0.3048)
			(stroke
				(width 0.1)
				(type default)
			)
			(layer "B.Fab")
		)
		(fp_line
			(start 0.12065 0.2794)
			(end 0.12065 0.3048)
			(stroke
				(width 0.1)
				(type default)
			)
			(layer "B.Fab")
		)
		(fp_line
			(start -0.120396 0.2794)
			(end 0.12065 0.2794)
			(stroke
				(width 0.1)
				(type default)
			)
			(layer "B.Fab")
		)
		(fp_line
			(start 0.67945 0.3048)
			(end 0.67945 -0.305054)
			(stroke
				(width 0.1)
				(type default)
			)
			(layer "B.Fab")
		)
		(fp_line
			(start 0.12065 0.3048)
			(end 0.67945 0.3048)
			(stroke
				(width 0.1)
				(type default)
			)
			(layer "B.Fab")
		)
		(fp_line
			(start -0.120396 0.3048)
			(end -0.120396 0.2794)
			(stroke
				(width 0.1)
				(type default)
			)
			(layer "B.Fab")
		)
		(fp_line
			(start -0.67945 0.3048)
			(end -0.120396 0.3048)
			(stroke
				(width 0.1)
				(type default)
			)
			(layer "B.Fab")
		)
		(pad "1" smd circle
			(at 0.40005 0 270)
			(size 0 0)
			(layers "B.Cu" "B.Mask" "B.Paste")
			(net "IRQ_SGPIO_R_N")
		)
		(pad "2" smd circle
			(at -0.40005 0 270)
			(size 0 0)
			(layers "B.Cu" "B.Mask" "B.Paste")
			(net "IRQ_SGPIO_N")
		)
	)
)
